(kicad_pcb
	(version 20260206)
	(generator "pcbnew")
	(generator_version "10.0")
	(general
		(thickness 1.6)
		(legacy_teardrops no)
	)
	(paper "A4")
	(title_block
		(title "Bryce Canyon_R.DPB_16317-1_OCP.brd")
		(comment 1 "Bryce Canyon / footprints 1749-1755 of 2099")
	)
	(layers
		(0 "F.Cu" signal "TOP")
		(4 "In1.Cu" signal "L2GND")
		(6 "In2.Cu" signal "L3")
		(8 "In3.Cu" signal "L4VCC")
		(10 "In4.Cu" signal "L5VCC")
		(12 "In5.Cu" signal "L6")
		(14 "In6.Cu" signal "L7GND")
		(2 "B.Cu" signal "BOTTOM")
		(9 "F.Adhes" user "F.Adhesive")
		(11 "B.Adhes" user "B.Adhesive")
		(13 "F.Paste" user "Package Geometry/Pastemask Top")
		(15 "B.Paste" user "Package Geometry/Pastemask Bottom")
		(5 "F.SilkS" user "Ref Des/Silkscreen Top")
		(7 "B.SilkS" user "Ref Des/Silkscreen Bottom")
		(1 "F.Mask" user "Board Geometry/Soldermask Top")
		(3 "B.Mask" user "Board Geometry/Soldermask Bottom")
		(17 "Dwgs.User" user "User.Drawings")
		(19 "Cmts.User" user "User.Comments")
		(21 "Eco1.User" user "User.Eco1")
		(23 "Eco2.User" user "User.Eco2")
		(25 "Edge.Cuts" user "Board Geometry/Outline")
		(27 "Margin" user)
		(31 "F.CrtYd" user "Package Geometry/Place Bound Top")
		(29 "B.CrtYd" user "Package Geometry/Place Bound Bottom")
		(35 "F.Fab" user "Ref Des/Assembly Top")
		(33 "B.Fab" user "Ref Des/Assembly Bottom")
	)
	(footprint ""
		(layer "F.Cu")
		(at 461.899 -131.826 180)
		(property "Reference" "R593"
			(at 0 0 180)
			(layer "F.SilkS")
			(hide yes)
			(effects
				(font
					(size 1.27 1.27)
				)
			)
		)
		(property "Value" "0R2J-2-GP"
			(at 0.064008 -3.993896 180)
			(unlocked yes)
			(layer "F.Fab")
			(hide yes)
			(effects
				(font
					(size 1.016 1.016)
					(thickness 0.1524)
				)
			)
		)
		(property "Device Type" "R402H16"
			(at 0.064008 -5.517896 180)
			(unlocked yes)
			(layer "F.Fab")
			(hide yes)
			(effects
				(font
					(size 1.016 1.016)
					(thickness 0.1524)
				)
			)
		)
		(duplicate_pad_numbers_are_jumpers no)
		(fp_line
			(start 0.508 -0.9398)
			(end -0.508 -0.9398)
			(stroke
				(width 0.1524)
				(type default)
			)
			(layer "F.SilkS")
		)
		(fp_line
			(start -0.508 -0.9398)
			(end -0.508 0.9398)
			(stroke
				(width 0.1524)
				(type default)
			)
			(layer "F.SilkS")
		)
		(fp_rect
			(start -0.508 0.9398)
			(end 0.508 -0.9398)
			(stroke
				(width 0)
				(type default)
			)
			(fill no)
			(layer "F.CrtYd")
		)
		(fp_rect
			(start -0.508 0.9398)
			(end 0.508 -0.9398)
			(stroke
				(width 0)
				(type default)
			)
			(fill no)
			(layer "F.Fab")
		)
		(pad "1" smd custom
			(at 0 -0.4445 180)
			(size 0.1397 0.1397)
			(layers "F.Cu" "F.Mask" "F.Paste")
			(net "SW_HDD_G22")
			(options
				(clearance outline)
				(anchor circle)
			)
			(primitives
				(gr_poly
					(pts
						(arc
							(start -0.1778 -0.2794)
							(mid -0.249642 -0.249642)
							(end -0.2794 -0.1778)
						)
						(arc
							(start -0.2794 0.1778)
							(mid -0.249642 0.249642)
							(end -0.1778 0.2794)
						)
						(arc
							(start 0.1778 0.2794)
							(mid 0.249642 0.249642)
							(end 0.2794 0.1778)
						)
						(arc
							(start 0.2794 -0.1778)
							(mid 0.249642 -0.249642)
							(end 0.1778 -0.2794)
						)
					)
					(width 0)
					(fill yes)
				)
			)
		)
		(pad "2" smd custom
			(at 0 0.4445 180)
			(size 0.1397 0.1397)
			(layers "F.Cu" "F.Mask" "F.Paste")
			(net "SW_HDD_R22")
			(options
				(clearance outline)
				(anchor circle)
			)
			(primitives
				(gr_poly
					(pts
						(arc
							(start -0.1778 -0.2794)
							(mid -0.249642 -0.249642)
							(end -0.2794 -0.1778)
						)
						(arc
							(start -0.2794 0.1778)
							(mid -0.249642 0.249642)
							(end -0.1778 0.2794)
						)
						(arc
							(start 0.1778 0.2794)
							(mid 0.249642 0.249642)
							(end 0.2794 0.1778)
						)
						(arc
							(start 0.2794 -0.1778)
							(mid 0.249642 -0.249642)
							(end 0.1778 -0.2794)
						)
					)
					(width 0)
					(fill yes)
				)
			)
		)
	)
	(footprint ""
		(layer "F.Cu")
		(at 127.9906 -31.623 180)
		(property "Reference" "R691"
			(at 0 0 180)
			(layer "F.SilkS")
			(hide yes)
			(effects
				(font
					(size 1.27 1.27)
				)
			)
		)
		(property "Value" "10KR2F-2-GP"
			(at 0.064008 -3.993896 180)
			(unlocked yes)
			(layer "F.Fab")
			(hide yes)
			(effects
				(font
					(size 1.016 1.016)
					(thickness 0.1524)
				)
			)
		)
		(property "Device Type" "R402H16"
			(at 0.064008 -5.517896 180)
			(unlocked yes)
			(layer "F.Fab")
			(hide yes)
			(effects
				(font
					(size 1.016 1.016)
					(thickness 0.1524)
				)
			)
		)
		(duplicate_pad_numbers_are_jumpers no)
		(fp_line
			(start 0.508 -0.9398)
			(end -0.508 -0.9398)
			(stroke
				(width 0.1524)
				(type default)
			)
			(layer "F.SilkS")
		)
		(fp_line
			(start -0.508 -0.9398)
			(end -0.508 0.9398)
			(stroke
				(width 0.1524)
				(type default)
			)
			(layer "F.SilkS")
		)
		(fp_rect
			(start -0.508 0.9398)
			(end 0.508 -0.9398)
			(stroke
				(width 0)
				(type default)
			)
			(fill no)
			(layer "F.CrtYd")
		)
		(fp_rect
			(start -0.508 0.9398)
			(end 0.508 -0.9398)
			(stroke
				(width 0)
				(type default)
			)
			(fill no)
			(layer "F.Fab")
		)
		(pad "1" smd custom
			(at 0 -0.4445 180)
			(size 0.1397 0.1397)
			(layers "F.Cu" "F.Mask" "F.Paste")
			(net "P3V3_STBY_B")
			(options
				(clearance outline)
				(anchor circle)
			)
			(primitives
				(gr_poly
					(pts
						(arc
							(start -0.1778 -0.2794)
							(mid -0.249642 -0.249642)
							(end -0.2794 -0.1778)
						)
						(arc
							(start -0.2794 0.1778)
							(mid -0.249642 0.249642)
							(end -0.1778 0.2794)
						)
						(arc
							(start 0.1778 0.2794)
							(mid 0.249642 0.249642)
							(end 0.2794 0.1778)
						)
						(arc
							(start 0.2794 -0.1778)
							(mid 0.249642 -0.249642)
							(end 0.1778 -0.2794)
						)
					)
					(width 0)
					(fill yes)
				)
			)
		)
		(pad "2" smd custom
			(at 0 0.4445 180)
			(size 0.1397 0.1397)
			(layers "F.Cu" "F.Mask" "F.Paste")
			(net "HDD_PRSNT_27")
			(options
				(clearance outline)
				(anchor circle)
			)
			(primitives
				(gr_poly
					(pts
						(arc
							(start -0.1778 -0.2794)
							(mid -0.249642 -0.249642)
							(end -0.2794 -0.1778)
						)
						(arc
							(start -0.2794 0.1778)
							(mid -0.249642 0.249642)
							(end -0.1778 0.2794)
						)
						(arc
							(start 0.1778 0.2794)
							(mid 0.249642 0.249642)
							(end 0.2794 0.1778)
						)
						(arc
							(start 0.2794 -0.1778)
							(mid 0.249642 -0.249642)
							(end 0.1778 -0.2794)
						)
					)
					(width 0)
					(fill yes)
				)
			)
		)
	)
	(footprint ""
		(layer "F.Cu")
		(at 51.562 -32.004 -90)
		(property "Reference" "C356"
			(at 0 0 270)
			(layer "F.SilkS")
			(hide yes)
			(effects
				(font
					(size 1.27 1.27)
				)
			)
		)
		(property "Value" "SC10U16V6KX-2GP"
			(at -0.0762 -5.1308 270)
			(unlocked yes)
			(layer "F.Fab")
			(hide yes)
			(effects
				(font
					(size 1.016 1.016)
					(thickness 0.1524)
				)
			)
		)
		(property "Device Type" "C1206H71"
			(at -0.127 -6.6548 270)
			(unlocked yes)
			(layer "F.Fab")
			(hide yes)
			(effects
				(font
					(size 1.016 1.016)
					(thickness 0.1524)
				)
			)
		)
		(duplicate_pad_numbers_are_jumpers no)
		(fp_line
			(start -1.016 2.2352)
			(end -1.016 0.8382)
			(stroke
				(width 0.1524)
				(type default)
			)
			(layer "F.SilkS")
		)
		(fp_line
			(start 1.016 2.2352)
			(end -1.016 2.2352)
			(stroke
				(width 0.1524)
				(type default)
			)
			(layer "F.SilkS")
		)
		(fp_line
			(start 1.016 0.8382)
			(end 1.016 2.2352)
			(stroke
				(width 0.1524)
				(type default)
			)
			(layer "F.SilkS")
		)
		(fp_line
			(start -1.016 -0.8382)
			(end -1.016 -2.2352)
			(stroke
				(width 0.1524)
				(type default)
			)
			(layer "F.SilkS")
		)
		(fp_line
			(start -1.016 -2.2352)
			(end 1.016 -2.2352)
			(stroke
				(width 0.1524)
				(type default)
			)
			(layer "F.SilkS")
		)
		(fp_line
			(start 1.016 -2.2352)
			(end 1.016 -0.8382)
			(stroke
				(width 0.1524)
				(type default)
			)
			(layer "F.SilkS")
		)
		(fp_rect
			(start -1.0922 2.3114)
			(end 1.0922 -2.3114)
			(stroke
				(width 0)
				(type default)
			)
			(fill no)
			(layer "F.CrtYd")
		)
		(fp_poly
			(pts
				(xy 1.0922 -2.3114) (xy 1.0922 2.3114) (xy -1.0922 2.3114) (xy -1.0922 -2.3114)
			)
			(stroke
				(width 0)
				(type default)
			)
			(fill no)
			(layer "F.Fab")
		)
		(pad "1" smd rect
			(at 0 -1.397 270)
			(size 1.651 1.27)
			(layers "F.Cu" "F.Mask" "F.Paste")
			(net "P5V_HDD25")
		)
		(pad "2" smd rect
			(at 0 1.397 270)
			(size 1.651 1.27)
			(layers "F.Cu" "F.Mask" "F.Paste")
			(net "GND")
		)
	)
	(footprint ""
		(layer "F.Cu")
		(at 366.395 -253.873 -90)
		(property "Reference" "Q26"
			(at 0 0 270)
			(layer "F.SilkS")
			(hide yes)
			(effects
				(font
					(size 1.27 1.27)
				)
			)
		)
		(property "Value" "AO4406AL-GP"
			(at -3.707384 -1.5367 270)
			(unlocked yes)
			(layer "F.Fab")
			(hide yes)
			(effects
				(font
					(size 1.016 1.016)
					(thickness 0.1524)
				)
			)
		)
		(property "Device Type" "SOIC8H69"
			(at -3.707384 -3.0607 270)
			(unlocked yes)
			(layer "F.Fab")
			(hide yes)
			(effects
				(font
					(size 1.016 1.016)
					(thickness 0.1524)
				)
			)
		)
		(duplicate_pad_numbers_are_jumpers no)
		(fp_line
			(start -2.6289 3.4417)
			(end -2.6289 1.4732)
			(stroke
				(width 0.381)
				(type default)
			)
			(layer "F.SilkS")
		)
		(fp_line
			(start -2.7432 1.4224)
			(end -2.6416 1.4224)
			(stroke
				(width 0.1524)
				(type default)
			)
			(layer "F.SilkS")
		)
		(fp_line
			(start -2.7432 1.4224)
			(end 2.1336 1.4224)
			(stroke
				(width 0.1524)
				(type default)
			)
			(layer "F.SilkS")
		)
		(fp_line
			(start 2.1336 1.4224)
			(end 2.1336 -1.4224)
			(stroke
				(width 0.1524)
				(type default)
			)
			(layer "F.SilkS")
		)
		(fp_line
			(start -2.1844 -0.0508)
			(end -2.7178 0.508)
			(stroke
				(width 0.1524)
				(type default)
			)
			(layer "F.SilkS")
		)
		(fp_line
			(start -2.7178 -0.508)
			(end -2.1844 -0.0508)
			(stroke
				(width 0.1524)
				(type default)
			)
			(layer "F.SilkS")
		)
		(fp_line
			(start -2.7432 -1.4224)
			(end -2.7432 1.4224)
			(stroke
				(width 0.1524)
				(type default)
			)
			(layer "F.SilkS")
		)
		(fp_line
			(start 2.1336 -1.4224)
			(end -2.7432 -1.4224)
			(stroke
				(width 0.1524)
				(type default)
			)
			(layer "F.SilkS")
		)
		(fp_poly
			(pts
				(xy -2.2098 -1.4224) (xy -2.2098 1.4224) (xy 2.2098 1.4224) (xy 2.2098 -1.4224)
			)
			(stroke
				(width 0)
				(type default)
			)
			(fill yes)
			(layer "F.SilkS")
		)
		(fp_rect
			(start -2.450084 2.999994)
			(end 2.450084 -2.999994)
			(stroke
				(width 0)
				(type default)
			)
			(fill no)
			(layer "F.CrtYd")
		)
		(fp_poly
			(pts
				(xy -2.8194 3.6322) (xy -2.8194 -3.6322) (xy 2.8194 -3.6322) (xy 2.8194 1.18364) (xy 2.450084 1.18364)
				(xy 2.450084 -2.999994) (xy -2.450084 -2.999994) (xy -2.450084 2.999994) (xy 2.450084 2.999994)
				(xy 2.450084 1.18618) (xy 2.8194 1.18618) (xy 2.8194 3.6322)
			)
			(stroke
				(width 0)
				(type default)
			)
			(fill no)
			(layer "F.CrtYd")
		)
		(fp_rect
			(start -2.8194 3.6322)
			(end 2.8194 -3.6322)
			(stroke
				(width 0)
				(type default)
			)
			(fill no)
			(layer "F.Fab")
		)
		(pad "1" smd rect
			(at -1.905 2.54 270)
			(size 0.635 1.651)
			(layers "F.Cu" "F.Mask" "F.Paste")
			(net "P5V_HDD7")
		)
		(pad "2" smd rect
			(at -0.635 2.54 270)
			(size 0.635 1.651)
			(layers "F.Cu" "F.Mask" "F.Paste")
			(net "P5V_HDD7")
		)
		(pad "3" smd rect
			(at 0.635 2.54 270)
			(size 0.635 1.651)
			(layers "F.Cu" "F.Mask" "F.Paste")
			(net "P5V_HDD7")
		)
		(pad "4" smd rect
			(at 1.905 2.54 270)
			(size 0.635 1.651)
			(layers "F.Cu" "F.Mask" "F.Paste")
			(net "SW_HDD_P7")
		)
		(pad "5" smd rect
			(at 1.905 -2.54 270)
			(size 0.635 1.651)
			(layers "F.Cu" "F.Mask" "F.Paste")
			(net "P5V_B_3")
		)
		(pad "6" smd rect
			(at 0.635 -2.54 270)
			(size 0.635 1.651)
			(layers "F.Cu" "F.Mask" "F.Paste")
			(net "P5V_B_3")
		)
		(pad "7" smd rect
			(at -0.635 -2.54 270)
			(size 0.635 1.651)
			(layers "F.Cu" "F.Mask" "F.Paste")
			(net "P5V_B_3")
		)
		(pad "8" smd rect
			(at -1.905 -2.54 270)
			(size 0.635 1.651)
			(layers "F.Cu" "F.Mask" "F.Paste")
			(net "P5V_B_3")
		)
	)
	(footprint ""
		(layer "F.Cu")
		(at 424.434 -275.336 180)
		(property "Reference" "C153"
			(at 0 0 180)
			(layer "F.SilkS")
			(hide yes)
			(effects
				(font
					(size 1.27 1.27)
				)
			)
		)
		(property "Value" "SC1U25V3KX-GP"
			(at 0 -2.8194 180)
			(unlocked yes)
			(layer "F.Fab")
			(hide yes)
			(effects
				(font
					(size 1.016 1.016)
					(thickness 0.1524)
				)
			)
		)
		(property "Device Type" "C603H36"
			(at 0 -4.3434 180)
			(unlocked yes)
			(layer "F.Fab")
			(hide yes)
			(effects
				(font
					(size 1.016 1.016)
					(thickness 0.1524)
				)
			)
		)
		(duplicate_pad_numbers_are_jumpers no)
		(fp_line
			(start 0.508 0)
			(end -0.508 0)
			(stroke
				(width 0.2032)
				(type default)
			)
			(layer "F.SilkS")
		)
		(fp_rect
			(start -0.5842 1.3335)
			(end 0.5842 -1.3335)
			(stroke
				(width 0)
				(type default)
			)
			(fill no)
			(layer "F.CrtYd")
		)
		(fp_rect
			(start -0.5842 1.3335)
			(end 0.5842 -1.3335)
			(stroke
				(width 0)
				(type default)
			)
			(fill no)
			(layer "F.Fab")
		)
		(pad "1" smd custom
			(at 0 -0.762 180)
			(size 0.2159 0.2159)
			(layers "F.Cu" "F.Mask" "F.Paste")
			(net "P12V_HDD9")
			(options
				(clearance outline)
				(anchor circle)
			)
			(primitives
				(gr_poly
					(pts
						(arc
							(start -0.3302 -0.4318)
							(mid -0.402042 -0.402042)
							(end -0.4318 -0.3302)
						)
						(arc
							(start -0.4318 0.3302)
							(mid -0.402042 0.402042)
							(end -0.3302 0.4318)
						)
						(arc
							(start 0.3302 0.4318)
							(mid 0.402042 0.402042)
							(end 0.4318 0.3302)
						)
						(arc
							(start 0.4318 -0.3302)
							(mid 0.402042 -0.402042)
							(end 0.3302 -0.4318)
						)
					)
					(width 0)
					(fill yes)
				)
			)
		)
		(pad "2" smd custom
			(at 0 0.762 180)
			(size 0.2159 0.2159)
			(layers "F.Cu" "F.Mask" "F.Paste")
			(net "GND")
			(options
				(clearance outline)
				(anchor circle)
			)
			(primitives
				(gr_poly
					(pts
						(arc
							(start -0.3302 -0.4318)
							(mid -0.402042 -0.402042)
							(end -0.4318 -0.3302)
						)
						(arc
							(start -0.4318 0.3302)
							(mid -0.402042 0.402042)
							(end -0.3302 0.4318)
						)
						(arc
							(start 0.3302 0.4318)
							(mid 0.402042 0.402042)
							(end 0.4318 0.3302)
						)
						(arc
							(start 0.4318 -0.3302)
							(mid 0.402042 -0.402042)
							(end 0.3302 -0.4318)
						)
					)
					(width 0)
					(fill yes)
				)
			)
		)
	)
	(footprint ""
		(layer "F.Cu")
		(at 141.097 -16.637 90)
		(property "Reference" "R728"
			(at 0 0 90)
			(layer "F.SilkS")
			(hide yes)
			(effects
				(font
					(size 1.27 1.27)
				)
			)
		)
		(property "Value" "4K7R2J-2-GP"
			(at 0.064008 -3.993896 90)
			(unlocked yes)
			(layer "F.Fab")
			(hide yes)
			(effects
				(font
					(size 1.016 1.016)
					(thickness 0.1524)
				)
			)
		)
		(property "Device Type" "R402H16"
			(at 0.064008 -5.517896 90)
			(unlocked yes)
			(layer "F.Fab")
			(hide yes)
			(effects
				(font
					(size 1.016 1.016)
					(thickness 0.1524)
				)
			)
		)
		(duplicate_pad_numbers_are_jumpers no)
		(fp_line
			(start 0.508 -0.9398)
			(end -0.508 -0.9398)
			(stroke
				(width 0.1524)
				(type default)
			)
			(layer "F.SilkS")
		)
		(fp_line
			(start -0.508 -0.9398)
			(end -0.508 0.9398)
			(stroke
				(width 0.1524)
				(type default)
			)
			(layer "F.SilkS")
		)
		(fp_rect
			(start -0.508 0.9398)
			(end 0.508 -0.9398)
			(stroke
				(width 0)
				(type default)
			)
			(fill no)
			(layer "F.CrtYd")
		)
		(fp_rect
			(start -0.508 0.9398)
			(end 0.508 -0.9398)
			(stroke
				(width 0)
				(type default)
			)
			(fill no)
			(layer "F.Fab")
		)
		(pad "1" smd custom
			(at 0 -0.4445 90)
			(size 0.1397 0.1397)
			(layers "F.Cu" "F.Mask" "F.Paste")
			(net "P12V_B")
			(options
				(clearance outline)
				(anchor circle)
			)
			(primitives
				(gr_poly
					(pts
						(arc
							(start -0.1778 -0.2794)
							(mid -0.249642 -0.249642)
							(end -0.2794 -0.1778)
						)
						(arc
							(start -0.2794 0.1778)
							(mid -0.249642 0.249642)
							(end -0.1778 0.2794)
						)
						(arc
							(start 0.1778 0.2794)
							(mid 0.249642 0.249642)
							(end 0.2794 0.1778)
						)
						(arc
							(start 0.2794 -0.1778)
							(mid 0.249642 -0.249642)
							(end 0.1778 -0.2794)
						)
					)
					(width 0)
					(fill yes)
				)
			)
		)
		(pad "2" smd custom
			(at 0 0.4445 90)
			(size 0.1397 0.1397)
			(layers "F.Cu" "F.Mask" "F.Paste")
			(net "SW_HDD_R28")
			(options
				(clearance outline)
				(anchor circle)
			)
			(primitives
				(gr_poly
					(pts
						(arc
							(start -0.1778 -0.2794)
							(mid -0.249642 -0.249642)
							(end -0.2794 -0.1778)
						)
						(arc
							(start -0.2794 0.1778)
							(mid -0.249642 0.249642)
							(end -0.1778 0.2794)
						)
						(arc
							(start 0.1778 0.2794)
							(mid 0.249642 0.249642)
							(end 0.2794 0.1778)
						)
						(arc
							(start 0.2794 -0.1778)
							(mid 0.249642 -0.249642)
							(end 0.1778 -0.2794)
						)
					)
					(width 0)
					(fill yes)
				)
			)
		)
	)
	(footprint ""
		(layer "F.Cu")
		(at 77.851 -35.687 -90)
		(property "Reference" "C372"
			(at 0 0 270)
			(layer "F.SilkS")
			(hide yes)
			(effects
				(font
					(size 1.27 1.27)
				)
			)
		)
		(property "Value" "SC4D7U25V5KX-1-GP"
			(at -0.0762 -6.1214 270)
			(unlocked yes)
			(layer "F.Fab")
			(hide yes)
			(effects
				(font
					(size 1.016 1.016)
					(thickness 0.1524)
				)
			)
		)
		(property "Device Type" "C805H58"
			(at -0.0762 -8.1534 270)
			(unlocked yes)
			(layer "F.Fab")
			(hide yes)
			(effects
				(font
					(size 1.016 1.016)
					(thickness 0.1524)
				)
			)
		)
		(duplicate_pad_numbers_are_jumpers no)
		(fp_line
			(start 0.635 0)
			(end -0.635 0)
			(stroke
				(width 0.508)
				(type default)
			)
			(layer "F.SilkS")
		)
		(fp_rect
			(start -0.9652 1.778)
			(end 0.9652 -1.778)
			(stroke
				(width 0)
				(type default)
			)
			(fill no)
			(layer "F.CrtYd")
		)
		(fp_poly
			(pts
				(xy -0.9652 -1.778) (xy 0.9652 -1.778) (xy 0.9652 1.778) (xy -0.9652 1.778)
			)
			(stroke
				(width 0)
				(type default)
			)
			(fill no)
			(layer "F.Fab")
		)
		(pad "1" smd rect
			(at 0 -0.9652 270)
			(size 1.397 1.143)
			(layers "F.Cu" "F.Mask" "F.Paste")
			(net "P12V_HDD26")
		)
		(pad "2" smd rect
			(at 0 0.9652 270)
			(size 1.397 1.143)
			(layers "F.Cu" "F.Mask" "F.Paste")
			(net "GND")
		)
	)
)
